FILE_TYPE=LIBRARY_PARTS;
primitive 'GTL2014','GTL2014_SM';
  pin
    'A0':
      PIN_NUMBER='(13)';
      BIDIRECTIONAL='TRUE';
      INPUT_LOAD='(-0.01,0.01)';
      OUTPUT_LOAD='(1.0,-1.0)';
    'A1':
      PIN_NUMBER='(12)';
      BIDIRECTIONAL='TRUE';
      INPUT_LOAD='(-0.01,0.01)';
      OUTPUT_LOAD='(1.0,-1.0)';
    'A2':
      PIN_NUMBER='(10)';
      BIDIRECTIONAL='TRUE';
      INPUT_LOAD='(-0.01,0.01)';
      OUTPUT_LOAD='(1.0,-1.0)';
    'A3':
      PIN_NUMBER='(9)';
      BIDIRECTIONAL='TRUE';
      INPUT_LOAD='(-0.01,0.01)';
      OUTPUT_LOAD='(1.0,-1.0)';
    'B0':
      PIN_NUMBER='(2)';
      BIDIRECTIONAL='TRUE';
      INPUT_LOAD='(-0.01,0.01)';
      OUTPUT_LOAD='(1.0,-1.0)';
    'B1':
      PIN_NUMBER='(3)';
      BIDIRECTIONAL='TRUE';
      INPUT_LOAD='(-0.01,0.01)';
      OUTPUT_LOAD='(1.0,-1.0)';
    'B2':
      PIN_NUMBER='(5)';
      BIDIRECTIONAL='TRUE';
      INPUT_LOAD='(-0.01,0.01)';
      OUTPUT_LOAD='(1.0,-1.0)';
    'B3':
      PIN_NUMBER='(6)';
      BIDIRECTIONAL='TRUE';
      INPUT_LOAD='(-0.01,0.01)';
      OUTPUT_LOAD='(1.0,-1.0)';
    'DIR':
      PIN_NUMBER='(1)';
      INPUT_LOAD='(-0.01,0.01)';
    'GND'<2>:
      PIN_NUMBER='(11)';
      PINUSE='GROUND';
      NO_LOAD_CHECK='Both';
      NO_IO_CHECK='Both';
      NO_ASSERT_CHECK='TRUE';
      NO_DIR_CHECK='TRUE';
      ALLOW_CONNECT='TRUE';
    'GND'<1>:
      PIN_NUMBER='(8)';
      PINUSE='GROUND';
      NO_LOAD_CHECK='Both';
      NO_IO_CHECK='Both';
      NO_ASSERT_CHECK='TRUE';
      NO_DIR_CHECK='TRUE';
      ALLOW_CONNECT='TRUE';
    'GND'<0>:
      PIN_NUMBER='(7)';
      PINUSE='GROUND';
      NO_LOAD_CHECK='Both';
      NO_IO_CHECK='Both';
      NO_ASSERT_CHECK='TRUE';
      NO_DIR_CHECK='TRUE';
      ALLOW_CONNECT='TRUE';
    'VCC':
      PIN_NUMBER='(14)';
      PINUSE='POWER';
      NO_LOAD_CHECK='Both';
      NO_IO_CHECK='Both';
      NO_ASSERT_CHECK='TRUE';
      NO_DIR_CHECK='TRUE';
      ALLOW_CONNECT='TRUE';
    'VREF':
      PIN_NUMBER='(4)';
      PINUSE='POWER';
      NO_LOAD_CHECK='Both';
      NO_IO_CHECK='Both';
      NO_ASSERT_CHECK='TRUE';
      NO_DIR_CHECK='TRUE';
      ALLOW_CONNECT='TRUE';
  end_pin;
  body
    PART_NAME='GTL2014';
    PHYS_DES_PREFIX='U';
  end_body;
end_primitive;

END.
